(kicad_pcb
	(version 20221018)
	(generator pcbnew)
	(general
    (thickness 1.6)
  )
	(paper "A4")
	(title_block
    (title "NUC Computer Cluster Power Breakout HW")
    (date "2023-10-18")
    (rev "1.4.3")
    (company "Antmicro Ltd.")
		(comment 9 "footprints 199-206 of 234")
	)
	(layers
    (0 "F.Cu" mixed)
    (1 "In1.Cu" power)
    (2 "In2.Cu" mixed)
    (31 "B.Cu" power)
    (32 "B.Adhes" user "B.Adhesive")
    (33 "F.Adhes" user "F.Adhesive")
    (34 "B.Paste" user)
    (35 "F.Paste" user)
    (36 "B.SilkS" user "B.Silkscreen")
    (37 "F.SilkS" user "F.Silkscreen")
    (38 "B.Mask" user)
    (39 "F.Mask" user)
    (40 "Dwgs.User" user "User.Drawings")
    (41 "Cmts.User" user "User.Comments")
    (42 "Eco1.User" user "User.Eco1")
    (43 "Eco2.User" user "User.Eco2")
    (44 "Edge.Cuts" user)
    (45 "Margin" user)
    (46 "B.CrtYd" user "B.Courtyard")
    (47 "F.CrtYd" user "F.Courtyard")
    (48 "B.Fab" user)
    (49 "F.Fab" user)
  )
	(footprint "antmicro-footprints:R_0402_1005Metric" (layer "F.Cu")
    (at 166.65 113.5 90)
    (descr "Resistor SMD 0402")
    (tags "resistor SMD 0402")
    (property "Author" "Antmicro")
    (property "License" "Apache-2.0")
    (property "MPN" "CR0402-FX-4701GLF")
    (property "Manufacturer" "Bourns")
    (property "Sheetfile" "ftdi-module.kicad_sch")
    (property "Sheetname" "FTDI")
    (property "Tolerance" "1%")
    (property "Val" "4k7")
    (property "ki_description" "SMD Chip Resistor, 4.7 kohm, ± 1%, 62.5 mW, 0402 [1005 Metric], Thick Film, General Purpose")
    (property "ki_keywords" "0402, SMT, RESISTOR, PASSIVE")
    (attr smd)
    (fp_text reference "R6" (at 0.9 0.4 90) (layer "F.SilkS")
        (effects (font (size 0.7 0.7) (thickness 0.15)) (justify left bottom))
    )
    (fp_text value "R_4k7_0402" (at -1.011843 1.772047 90) (layer "F.Fab")
        (effects (font (size 0.7 0.7) (thickness 0.15)) (justify left bottom))
    )
    (fp_text user "License: Apache-2.0" (at -0.95 5.169 90) (layer "F.Fab") hide
        (effects (font (size 0.7 0.7) (thickness 0.15)) (justify left bottom))
    )
    (fp_text user "${REFERENCE}" (at -0.95 3.168 90) (layer "F.Fab") hide
        (effects (font (size 0.7 0.7) (thickness 0.15)) (justify left bottom))
    )
    (fp_text user "Author: Antmicro" (at -0.95 4.169 90) (layer "F.Fab") hide
        (effects (font (size 0.7 0.7) (thickness 0.15)) (justify left bottom))
    )
    (fp_rect (start -0.925 -0.47) (end 0.925 0.47)
      (stroke (width 0.05) (type default)) (fill none) (layer "F.CrtYd"))
    (fp_rect (start -0.5 -0.25) (end 0.5 0.25)
      (stroke (width 0.15) (type solid)) (fill none) (layer "F.Fab"))
    (pad "1" smd roundrect (at -0.48 0 90) (size 0.59 0.64) (layers "F.Cu" "F.Paste" "F.Mask") (roundrect_rratio 0.25)
      (net 80 "SDA_FTDI") (pintype "passive"))
    (pad "2" smd roundrect (at 0.48 0 90) (size 0.59 0.64) (layers "F.Cu" "F.Paste" "F.Mask") (roundrect_rratio 0.25)
      (net 76 "VCC3V3_USB") (pintype "passive"))
  )
	(footprint "antmicro-footprints:C_0402_1005Metric" (layer "F.Cu")
    (at 172.1 101.82 90)
    (descr "Capacitor SMD 0402")
    (tags "capacitor SMD 0402")
    (property "Author" "Antmicro")
    (property "Dielectric" "X5R")
    (property "License" "Apache-2.0")
    (property "MPN" "GRM155R61H104KE14D")
    (property "Manufacturer" "Murata")
    (property "Sheetfile" "ftdi-module.kicad_sch")
    (property "Sheetname" "FTDI")
    (property "Val" "100n")
    (property "Voltage" "50V")
    (property "ki_description" "SMD Multilayer Ceramic Capacitor, 0.1 µF, 50 V, 0402 [1005 Metric], ± 10%, X5R, GRM Series")
    (property "ki_keywords" "0402, SMT, CAPACITOR, PASSIVE, CERAMIC, MLCC")
    (attr smd)
    (fp_text reference "C5" (at 1.695 0 90) (layer "F.SilkS")
        (effects (font (size 0.7 0.7) (thickness 0.15)))
    )
    (fp_text value "C_100n_0402" (at 0 1.17 90) (layer "F.Fab")
        (effects (font (size 1 1) (thickness 0.15)))
    )
    (fp_text user "${REFERENCE}" (at 0 0 90) (layer "F.Fab")
        (effects (font (size 0.25 0.25) (thickness 0.04)))
    )
    (fp_text user "Author: Antmicro" (at -0.939 3.399 90) (layer "F.Fab") hide
        (effects (font (size 0.7 0.7) (thickness 0.15)) (justify left bottom))
    )
    (fp_text user "License: Apache-2.0" (at -0.939 5.799 90) (layer "F.Fab") hide
        (effects (font (size 0.7 0.7) (thickness 0.15)) (justify left bottom))
    )
    (fp_rect (start -0.925 -0.47) (end 0.925 0.47)
      (stroke (width 0.05) (type default)) (fill none) (layer "F.CrtYd"))
    (fp_line (start -0.494 -0.25) (end 0.504 -0.25)
      (stroke (width 0.15) (type solid)) (layer "F.Fab"))
    (fp_line (start -0.494 0.248) (end -0.494 -0.25)
      (stroke (width 0.15) (type solid)) (layer "F.Fab"))
    (fp_line (start 0.504 -0.25) (end 0.504 0.248)
      (stroke (width 0.15) (type solid)) (layer "F.Fab"))
    (fp_line (start 0.504 0.248) (end -0.494 0.248)
      (stroke (width 0.15) (type solid)) (layer "F.Fab"))
    (pad "1" smd roundrect (at -0.48 0 90) (size 0.59 0.64) (layers "F.Cu" "F.Paste" "F.Mask") (roundrect_rratio 0.25)
      (net 4 "GND") (pintype "passive"))
    (pad "2" smd roundrect (at 0.48 0 90) (size 0.59 0.64) (layers "F.Cu" "F.Paste" "F.Mask") (roundrect_rratio 0.25)
      (net 1 "VCC3V3") (pintype "passive"))
  )
	(footprint "antmicro-footprints:R_0402_1005Metric" (layer "F.Cu")
    (at 166.315 101.6 -90)
    (descr "Resistor SMD 0402")
    (tags "resistor SMD 0402")
    (property "Author" "Antmicro")
    (property "License" "Apache-2.0")
    (property "MPN" "CR0402-FX-1002GLF")
    (property "Manufacturer" "Bourns")
    (property "Sheetfile" "ftdi-module.kicad_sch")
    (property "Sheetname" "FTDI")
    (property "Tolerance" "1%")
    (property "Val" "10k")
    (property "ki_description" "SMD Chip Resistor, 10 kohm, ± 1%, 62.5 mW, 0402 [1005 Metric], Thick Film, General Purpose")
    (property "ki_keywords" "0402, SMT, RESISTOR, PASSIVE")
    (attr smd)
    (fp_text reference "R73" (at 1.1 -1.485 -90) (layer "F.SilkS")
        (effects (font (size 0.7 0.7) (thickness 0.15)) (justify left bottom))
    )
    (fp_text value "R_10k_0402" (at -1.011843 1.772047 -90) (layer "F.Fab")
        (effects (font (size 0.7 0.7) (thickness 0.15)) (justify left bottom))
    )
    (fp_text user "Author: Antmicro" (at -0.95 4.169 -90) (layer "F.Fab") hide
        (effects (font (size 0.7 0.7) (thickness 0.15)) (justify left bottom))
    )
    (fp_text user "License: Apache-2.0" (at -0.95 5.169 -90) (layer "F.Fab") hide
        (effects (font (size 0.7 0.7) (thickness 0.15)) (justify left bottom))
    )
    (fp_text user "${REFERENCE}" (at -0.95 3.168 -90) (layer "F.Fab") hide
        (effects (font (size 0.7 0.7) (thickness 0.15)) (justify left bottom))
    )
    (fp_rect (start -0.925 -0.47) (end 0.925 0.47)
      (stroke (width 0.05) (type default)) (fill none) (layer "F.CrtYd"))
    (fp_rect (start -0.5 -0.25) (end 0.5 0.25)
      (stroke (width 0.15) (type solid)) (fill none) (layer "F.Fab"))
    (pad "1" smd roundrect (at -0.48 0 270) (size 0.59 0.64) (layers "F.Cu" "F.Paste" "F.Mask") (roundrect_rratio 0.25)
      (net 1 "VCC3V3") (pintype "passive"))
    (pad "2" smd roundrect (at 0.48 0 270) (size 0.59 0.64) (layers "F.Cu" "F.Paste" "F.Mask") (roundrect_rratio 0.25)
      (net 115 "Net-(U6-A)") (pintype "passive"))
  )
	(footprint "antmicro-footprints:R_0603_1608Metric" (layer "F.Cu")
    (at 181.6 55.75 -90)
    (descr "Resistor SMD 0603")
    (tags "resistor SMD 0603")
    (property "Author" "Antmicro")
    (property "License" "Apache-2.0")
    (property "MPN" "CR0603-FX-4701ELF")
    (property "Manufacturer" "Bourns")
    (property "Sheetfile" "d1600e-psu-breakout-board.kicad_sch")
    (property "Sheetname" "")
    (property "Tolerance" "1%")
    (property "Val" "4k7")
    (property "ki_description" "SMD Chip Resistor, 4.7 kohm, ± 1%, 100 mW, 0603 [1608 Metric], Thick Film, General Purpose")
    (property "ki_keywords" "0603, SMT, RESISTOR, PASSIVE")
    (attr smd)
    (fp_text reference "R53" (at 0.95 0.8 -90) (layer "F.SilkS")
        (effects (font (size 0.7 0.7) (thickness 0.15)) (justify left bottom))
    )
    (fp_text value "R_4k7_0603" (at 0 1.6 -90) (layer "F.Fab")
        (effects (font (size 0.7 0.7) (thickness 0.15)) (justify left bottom))
    )
    (fp_text user "License: Apache-2.0" (at -1.25 5.9 -90) (layer "F.Fab") hide
        (effects (font (size 0.7 0.7) (thickness 0.15)) (justify left bottom))
    )
    (fp_text user "Author: Antmicro" (at -1.25 4.9 -90) (layer "F.Fab") hide
        (effects (font (size 0.7 0.7) (thickness 0.15)) (justify left bottom))
    )
    (fp_text user "${REFERENCE}" (at -1.25 3.898 -90) (layer "F.Fab") hide
        (effects (font (size 0.7 0.7) (thickness 0.15)) (justify left bottom))
    )
    (fp_line (start -0.15 -0.4) (end 0.15 -0.4)
      (stroke (width 0.15) (type solid)) (layer "F.SilkS"))
    (fp_line (start -0.15 0.4) (end 0.15 0.4)
      (stroke (width 0.15) (type solid)) (layer "F.SilkS"))
    (fp_rect (start -1.25 -0.65) (end 1.25 0.65)
      (stroke (width 0.05) (type solid)) (fill none) (layer "F.CrtYd"))
    (fp_rect (start -0.8 -0.4) (end 0.8 0.4)
      (stroke (width 0.15) (type solid)) (fill none) (layer "F.Fab"))
    (pad "1" smd roundrect (at -0.7 0 270) (size 0.8 1) (layers "F.Cu" "F.Paste" "F.Mask") (roundrect_rratio 0.2)
      (net 53 "Net-(D8-A)") (pintype "passive"))
    (pad "2" smd roundrect (at 0.7 0 270) (size 0.8 1) (layers "F.Cu" "F.Paste" "F.Mask") (roundrect_rratio 0.2)
      (net 43 "LOAD_5") (pintype "passive"))
  )
	(footprint "antmicro-footprints:R_0402_1005Metric" (layer "F.Cu")
    (at 164.3 90.6 90)
    (descr "Resistor SMD 0402")
    (tags "resistor SMD 0402")
    (property "Author" "Antmicro")
    (property "License" "Apache-2.0")
    (property "MPN" "CR0402-FX-2R00GLF")
    (property "Manufacturer" "Bourns")
    (property "Sheetfile" "power-switch.kicad_sch")
    (property "Sheetname" "Power switch 4")
    (property "Tolerance" "1%")
    (property "Val" "2R")
    (property "ki_description" "SMD Chip Resistor")
    (property "ki_keywords" "0402, SMT, RESISTOR, PASSIVE")
    (attr smd)
    (fp_text reference "R66" (at -1.45 -0.55 90) (layer "F.SilkS")
        (effects (font (size 0.7 0.7) (thickness 0.15)) (justify left bottom))
    )
    (fp_text value "R_2R_0402" (at -1.011843 1.772047 90) (layer "F.Fab")
        (effects (font (size 0.7 0.7) (thickness 0.15)) (justify left bottom))
    )
    (fp_text user "${REFERENCE}" (at -0.95 3.168 90) (layer "F.Fab") hide
        (effects (font (size 0.7 0.7) (thickness 0.15)) (justify left bottom))
    )
    (fp_text user "Author: Antmicro" (at -0.95 4.169 90) (layer "F.Fab") hide
        (effects (font (size 0.7 0.7) (thickness 0.15)) (justify left bottom))
    )
    (fp_text user "License: Apache-2.0" (at -0.95 5.169 90) (layer "F.Fab") hide
        (effects (font (size 0.7 0.7) (thickness 0.15)) (justify left bottom))
    )
    (fp_rect (start -0.925 -0.47) (end 0.925 0.47)
      (stroke (width 0.05) (type default)) (fill none) (layer "F.CrtYd"))
    (fp_rect (start -0.5 -0.25) (end 0.5 0.25)
      (stroke (width 0.15) (type solid)) (fill none) (layer "F.Fab"))
    (pad "1" smd roundrect (at -0.48 0 90) (size 0.59 0.64) (layers "F.Cu" "F.Paste" "F.Mask") (roundrect_rratio 0.25)
      (net 85 "Net-(D17-A)") (pintype "passive"))
    (pad "2" smd roundrect (at 0.48 0 90) (size 0.59 0.64) (layers "F.Cu" "F.Paste" "F.Mask") (roundrect_rratio 0.25)
      (net 96 "Net-(QA4-G)") (pintype "passive"))
  )
	(footprint "antmicro-footprints:D_SOD-323" (layer "F.Cu")
    (at 135.3 91.6 -90)
    (property "Author" "Antmicro")
    (property "License" "Apache-2.0")
    (property "MPN" "BZT52B15SV-T")
    (property "Manufacturer" "Rectron")
    (property "Sheetfile" "power-switch.kicad_sch")
    (property "Sheetname" "Power switch 2")
    (property "ki_description" "Zener Single Diode, AEC-Q101, 15 V, 500 mW, SOD-323, 2 Pins, 150 °C, Surface Mount")
    (property "ki_keywords" "SMT, DIODE, SEMICONDUCTOR, ZENER")
    (attr smd)
    (fp_text reference "D16" (at 2.75 1.45) (layer "F.SilkS")
        (effects (font (size 0.7 0.7) (thickness 0.15)) (justify left bottom))
    )
    (fp_text value "BZT52B15SV-T" (at 0 1.841 -90) (layer "F.Fab")
        (effects (font (size 0.7 0.7) (thickness 0.15)) (justify left bottom))
    )
    (fp_text user "Author: Antmicro" (at -1.4 6.241 -90) (layer "F.Fab") hide
        (effects (font (size 0.7 0.7) (thickness 0.15)) (justify left bottom))
    )
    (fp_text user "${REFERENCE}" (at -1.4 5.041 -90) (layer "F.Fab") hide
        (effects (font (size 0.7 0.7) (thickness 0.15)) (justify left bottom))
    )
    (fp_text user "License: Apache-2.0" (at -1.4 3.841 -90) (layer "F.Fab") hide
        (effects (font (size 0.7 0.7) (thickness 0.15)) (justify left bottom))
    )
    (fp_line (start -0.949 -0.749) (end -0.949 -0.499)
      (stroke (width 0.15) (type solid)) (layer "F.SilkS"))
    (fp_line (start -0.949 0.501) (end -0.949 0.751)
      (stroke (width 0.15) (type solid)) (layer "F.SilkS"))
    (fp_line (start -0.6 -0.499) (end -0.6 0.499)
      (stroke (width 0.15) (type solid)) (layer "F.SilkS"))
    (fp_line (start -0.577 -0.749) (end -0.949 -0.749)
      (stroke (width 0.15) (type solid)) (layer "F.SilkS"))
    (fp_line (start -0.577 0.751) (end -0.949 0.751)
      (stroke (width 0.15) (type solid)) (layer "F.SilkS"))
    (fp_line (start 0.625 -0.736) (end 0.949 -0.736)
      (stroke (width 0.15) (type solid)) (layer "F.SilkS"))
    (fp_line (start 0.949 -0.736) (end 0.949 -0.499)
      (stroke (width 0.15) (type solid)) (layer "F.SilkS"))
    (fp_line (start 0.95 0.501) (end 0.95 0.751)
      (stroke (width 0.15) (type solid)) (layer "F.SilkS"))
    (fp_line (start 0.95 0.751) (end 0.649 0.751)
      (stroke (width 0.15) (type solid)) (layer "F.SilkS"))
    (fp_rect (start -1.6 -0.925) (end 1.6 0.925)
      (stroke (width 0.05) (type solid)) (fill none) (layer "F.CrtYd"))
    (fp_line (start -0.902 0.699) (end -0.902 -0.699)
      (stroke (width 0.15) (type solid)) (layer "F.Fab"))
    (fp_line (start -0.902 0.699) (end 0.9 0.699)
      (stroke (width 0.15) (type solid)) (layer "F.Fab"))
    (fp_line (start 0.9 -0.699) (end -0.902 -0.699)
      (stroke (width 0.15) (type solid)) (layer "F.Fab"))
    (fp_line (start 0.9 -0.699) (end 0.9 0.699)
      (stroke (width 0.15) (type solid)) (layer "F.Fab"))
    (pad "1" smd rect (at -1.125 0.001 270) (size 0.8 0.8) (layers "F.Cu" "F.Paste" "F.Mask")
      (net 11 "VCC12V0") (pinfunction "C") (pintype "passive"))
    (pad "2" smd rect (at 1.124 0.001 270) (size 0.8 0.8) (layers "F.Cu" "F.Paste" "F.Mask")
      (net 84 "Net-(D16-A)") (pinfunction "A") (pintype "passive"))
  )
	(footprint "antmicro-footprints:R_0402_1005Metric" (layer "F.Cu")
    (at 147.65 90.6 90)
    (descr "Resistor SMD 0402")
    (tags "resistor SMD 0402")
    (property "Author" "Antmicro")
    (property "License" "Apache-2.0")
    (property "MPN" "CR0402-FX-2R00GLF")
    (property "Manufacturer" "Bourns")
    (property "Sheetfile" "power-switch.kicad_sch")
    (property "Sheetname" "Power switch 3")
    (property "Tolerance" "1%")
    (property "Val" "2R")
    (property "ki_description" "SMD Chip Resistor")
    (property "ki_keywords" "0402, SMT, RESISTOR, PASSIVE")
    (attr smd)
    (fp_text reference "R67" (at -1.6 -0.7 90) (layer "F.SilkS")
        (effects (font (size 0.7 0.7) (thickness 0.15)) (justify left bottom))
    )
    (fp_text value "R_2R_0402" (at -1.011843 1.772047 90) (layer "F.Fab")
        (effects (font (size 0.7 0.7) (thickness 0.15)) (justify left bottom))
    )
    (fp_text user "${REFERENCE}" (at -0.95 3.168 90) (layer "F.Fab") hide
        (effects (font (size 0.7 0.7) (thickness 0.15)) (justify left bottom))
    )
    (fp_text user "License: Apache-2.0" (at -0.95 5.169 90) (layer "F.Fab") hide
        (effects (font (size 0.7 0.7) (thickness 0.15)) (justify left bottom))
    )
    (fp_text user "Author: Antmicro" (at -0.95 4.169 90) (layer "F.Fab") hide
        (effects (font (size 0.7 0.7) (thickness 0.15)) (justify left bottom))
    )
    (fp_rect (start -0.925 -0.47) (end 0.925 0.47)
      (stroke (width 0.05) (type default)) (fill none) (layer "F.CrtYd"))
    (fp_rect (start -0.5 -0.25) (end 0.5 0.25)
      (stroke (width 0.15) (type solid)) (fill none) (layer "F.Fab"))
    (pad "1" smd roundrect (at -0.48 0 90) (size 0.59 0.64) (layers "F.Cu" "F.Paste" "F.Mask") (roundrect_rratio 0.25)
      (net 86 "Net-(D18-A)") (pintype "passive"))
    (pad "2" smd roundrect (at 0.48 0 90) (size 0.59 0.64) (layers "F.Cu" "F.Paste" "F.Mask") (roundrect_rratio 0.25)
      (net 95 "Net-(QA3-G)") (pintype "passive"))
  )
	(footprint "antmicro-footprints:SC-70-5" (layer "F.Cu")
    (at 170.2 102.091 -90)
    (descr "5-lead Small Outline SMT package (aka SC-70-5, SC-88A or TSSOP5): reflow soldering footprint")
    (tags "SOT-353 sot353 SC-70-5 sc70 SC-88A sc88a TSSOP5")
    (property "Author" "Antmicro")
    (property "License" "Apache-2.0")
    (property "MPN" "SN74AUP1G17DCKR")
    (property "Manufacturer" "Texas Instruments")
    (property "Sheetfile" "ftdi-module.kicad_sch")
    (property "Sheetname" "FTDI")
    (property "ki_description" "Buffer, 74AUP1G17, 0.8 V to 3.6 V, TSSOP-5")
    (property "ki_keywords" "SMT, LOGIC, IC, BUFFER, TRANSCEIVER")
    (attr smd)
    (fp_text reference "U6" (at -1.421 0.71) (layer "F.SilkS")
        (effects (font (size 0.7 0.7) (thickness 0.15)) (justify left bottom))
    )
    (fp_text value "SN74AUP1G17_SC70" (at 0 2.4 90) (layer "F.Fab")
        (effects (font (size 0.7 0.7) (thickness 0.15)) (justify right bottom))
    )
    (fp_text user "License: Apache-2.0" (at -1.206 6.427 90) (layer "F.Fab") hide
        (effects (font (size 0.7 0.7) (thickness 0.15)) (justify right bottom))
    )
    (fp_text user "Author: Antmicro" (at -1.206 5.227 90) (layer "F.Fab") hide
        (effects (font (size 0.7 0.7) (thickness 0.15)) (justify right bottom))
    )
    (fp_text user "${REFERENCE}" (at -1.206 4.027 90) (layer "F.Fab") hide
        (effects (font (size 0.7 0.7) (thickness 0.15)) (justify right bottom))
    )
    (fp_line (start -1.156 0.694) (end -1.156 -0.705)
      (stroke (width 0.15) (type solid)) (layer "F.SilkS"))
    (fp_line (start 1.144 0.694) (end 1.144 -0.705)
      (stroke (width 0.15) (type solid)) (layer "F.SilkS"))
    (fp_circle (center -1.25 0.95) (end -1.19 1)
      (stroke (width 0.15) (type solid)) (fill solid) (layer "F.SilkS"))
    (fp_rect (start 1.25 -1.31) (end -1.25 1.3)
      (stroke (width 0.05) (type solid)) (fill none) (layer "F.CrtYd"))
    (fp_line (start -1.006 -0.657) (end 0.993 -0.657)
      (stroke (width 0.15) (type solid)) (layer "F.Fab"))
    (fp_line (start -1.006 0.293) (end -1.006 -0.657)
      (stroke (width 0.15) (type solid)) (layer "F.Fab"))
    (fp_line (start -1.006 0.293) (end -0.706 0.593)
      (stroke (width 0.15) (type solid)) (layer "F.Fab"))
    (fp_line (start 0.993 -0.657) (end 0.993 0.593)
      (stroke (width 0.15) (type solid)) (layer "F.Fab"))
    (fp_line (start 0.993 0.593) (end -0.706 0.593)
      (stroke (width 0.15) (type solid)) (layer "F.Fab"))
    (pad "1" smd roundrect (at -0.756 0.893) (size 0.6 0.6) (layers "F.Cu" "F.Paste" "F.Mask") (roundrect_rratio 0.25)
      (net 159 "unconnected-(U6-NC-Pad1)") (pinfunction "NC") (pintype "no_connect"))
    (pad "2" smd roundrect (at -0.006 0.893) (size 0.6 0.4) (layers "F.Cu" "F.Paste" "F.Mask") (roundrect_rratio 0.25)
      (net 115 "Net-(U6-A)") (pinfunction "A") (pintype "input"))
    (pad "3" smd roundrect (at 0.743 0.893) (size 0.6 0.6) (layers "F.Cu" "F.Paste" "F.Mask") (roundrect_rratio 0.25)
      (net 4 "GND") (pinfunction "GND") (pintype "power_in"))
    (pad "4" smd roundrect (at 0.743 -0.907) (size 0.6 0.6) (layers "F.Cu" "F.Paste" "F.Mask") (roundrect_rratio 0.25)
      (net 145 "LED_DATA") (pinfunction "Y") (pintype "output"))
    (pad "5" smd roundrect (at -0.756 -0.907) (size 0.6 0.6) (layers "F.Cu" "F.Paste" "F.Mask") (roundrect_rratio 0.25)
      (net 1 "VCC3V3") (pinfunction "VCC") (pintype "power_in"))
  )
)
